(kicad_pcb
	(version 20241229)
	(generator "pcbnew")
	(generator_version "9.0")
	(general
		(thickness 1.599998)
		(legacy_teardrops no)
	)
	(paper "A4")
	(title_block
		(title "Artix - Datacenter Secure Control Module (DC-SCM)")
		(date "2024-11-06")
		(rev "1.1.3")
		(comment 9 "footprint 110 of 544 (U14), pads 478-484 of 484")
	)
	(layers
		(0 "F.Cu" signal)
		(4 "In1.Cu" signal)
		(6 "In2.Cu" signal)
		(8 "In3.Cu" signal)
		(10 "In4.Cu" signal)
		(12 "In5.Cu" signal)
		(14 "In6.Cu" signal)
		(2 "B.Cu" signal)
		(9 "F.Adhes" user "F.Adhesive")
		(11 "B.Adhes" user "B.Adhesive")
		(13 "F.Paste" user)
		(15 "B.Paste" user)
		(5 "F.SilkS" user "F.Silkscreen")
		(7 "B.SilkS" user "B.Silkscreen")
		(1 "F.Mask" user)
		(3 "B.Mask" user)
		(17 "Dwgs.User" user "User.Drawings")
		(19 "Cmts.User" user "User.Comments")
		(21 "Eco1.User" user "User.Eco1")
		(23 "Eco2.User" user "User.Eco2")
		(25 "Edge.Cuts" user)
		(27 "Margin" user)
		(31 "F.CrtYd" user "F.Courtyard")
		(29 "B.CrtYd" user "B.Courtyard")
		(35 "F.Fab" user)
		(33 "B.Fab" user)
	)
	(footprint "antmicro-footprints:BGA-484_23x23mm_Layout22x22_P1mm_FGG484"
		(layer "F.Cu")
		(at 101.275 119.675 90)
		(property "Reference" "U14"
			(at 11.965 9.405 180)
			(layer "F.SilkS")
			(effects
				(font
					(size 0.7 0.7)
					(thickness 0.15)
				)
				(justify left bottom)
			)
		)
		(property "Value" "XC7A100T-FGG484"
			(at 0 13.1 90)
			(layer "F.Fab")
			(effects
				(font
					(size 0.7 0.7)
					(thickness 0.15)
				)
				(justify left bottom)
			)
		)
		(property "Datasheet" "https://docs.xilinx.com/v/u/en-US/ds181_Artix_7_Data_Sheet"
			(at 0 0 90)
			(layer "F.Fab")
			(hide yes)
			(effects
				(font
					(size 1.27 1.27)
					(thickness 0.15)
				)
			)
		)
		(property "Description" "Artix-7 Field Programmable Gate Array IC 210 324-LFBGA, CSPBGA"
			(at 0 0 90)
			(layer "F.Fab")
			(hide yes)
			(effects
				(font
					(size 1.27 1.27)
					(thickness 0.15)
				)
			)
		)
		(property "Author" "Antmicro"
			(at 220.95 18.4 0)
			(layer "F.Fab")
			(hide yes)
			(effects
				(font
					(size 1 1)
					(thickness 0.15)
				)
			)
		)
		(property "License" "Apache-2.0"
			(at 220.95 18.4 0)
			(layer "F.Fab")
			(hide yes)
			(effects
				(font
					(size 1 1)
					(thickness 0.15)
				)
			)
		)
		(property "MPN" "XC7A100T-FGG484"
			(at 220.95 18.4 0)
			(layer "F.Fab")
			(hide yes)
			(effects
				(font
					(size 1 1)
					(thickness 0.15)
				)
			)
		)
		(property "Manufacturer" "AMD-Xilinx"
			(at 220.95 18.4 0)
			(layer "F.Fab")
			(hide yes)
			(effects
				(font
					(size 1 1)
					(thickness 0.15)
				)
			)
		)
		(sheetname "/FPGA power supply/")
		(sheetfile "fpga-power-supply.kicad_sch")
		(solder_mask_margin 0.05)
		(attr smd)
		(pad "Y16" smd circle
			(at 4.498 8.499 90)
			(size 0.5 0.5)
			(layers "F.Cu" "F.Mask" "F.Paste")
			(net 644 "unconnected-(U14A-IO_L1P_T0_13-PadY16)")
			(pinfunction "IO_L1P_T0_13")
			(pintype "bidirectional+no_connect")
		)
		(pad "Y17" smd circle
			(at 5.499 8.499 90)
			(size 0.5 0.5)
			(layers "F.Cu" "F.Mask" "F.Paste")
			(net 645 "unconnected-(U14A-IO_0_13-PadY17)")
			(pinfunction "IO_0_13")
			(pintype "bidirectional+no_connect")
		)
		(pad "Y18" smd circle
			(at 6.499 8.499 90)
			(size 0.5 0.5)
			(layers "F.Cu" "F.Mask" "F.Paste")
			(net 330 "MMC_CLK")
			(pinfunction "IO_L13P_T2_MRCC_14")
			(pintype "bidirectional")
		)
		(pad "Y19" smd circle
			(at 7.499 8.499 90)
			(size 0.5 0.5)
			(layers "F.Cu" "F.Mask" "F.Paste")
			(net 329 "MMC_CMD")
			(pinfunction "IO_L13N_T2_MRCC_14")
			(pintype "bidirectional")
		)
		(pad "Y20" smd circle
			(at 8.499 8.499 90)
			(size 0.5 0.5)
			(layers "F.Cu" "F.Mask" "F.Paste")
			(net 2 "VCC3V3")
			(pinfunction "VCCO_14")
			(pintype "power_in")
		)
		(pad "Y21" smd circle
			(at 9.499 8.499 90)
			(size 0.5 0.5)
			(layers "F.Cu" "F.Mask" "F.Paste")
			(net 590 "TPM_GPIO")
			(pinfunction "IO_L9P_T1_DQS_14")
			(pintype "bidirectional")
		)
		(pad "Y22" smd circle
			(at 10.499 8.499 90)
			(size 0.5 0.5)
			(layers "F.Cu" "F.Mask" "F.Paste")
			(net 446 "ULPI1_STP")
			(pinfunction "IO_L9N_T1_DQS_D13_14")
			(pintype "bidirectional")
		)
	)
)
